(kicad_pcb
	(version 20221018)
	(generator pcbnew)
	(general
    (thickness 1.518)
  )
	(paper "A4")
	(title_block
    (title "Kria K26 Devboard")
    (date "2024-03-26")
    (rev "1.2.5")
    (comment 1 "www.antmicro.com")
    (comment 2 "Antmicro Ltd.")
		(comment 9 "footprints 442-448 of 660")
	)
	(layers
    (0 "F.Cu" mixed)
    (1 "In1.Cu" power)
    (2 "In2.Cu" mixed)
    (3 "In3.Cu" power)
    (4 "In4.Cu" mixed)
    (5 "In5.Cu" power)
    (6 "In6.Cu" mixed)
    (31 "B.Cu" power)
    (32 "B.Adhes" user "B.Adhesive")
    (33 "F.Adhes" user "F.Adhesive")
    (34 "B.Paste" user)
    (35 "F.Paste" user)
    (36 "B.SilkS" user "B.Silkscreen")
    (37 "F.SilkS" user "F.Silkscreen")
    (38 "B.Mask" user)
    (39 "F.Mask" user)
    (40 "Dwgs.User" user "User.Drawings")
    (41 "Cmts.User" user "User.Comments")
    (42 "Eco1.User" user "User.Eco1")
    (43 "Eco2.User" user "User.Eco2")
    (44 "Edge.Cuts" user)
    (45 "Margin" user)
    (46 "B.CrtYd" user "B.Courtyard")
    (47 "F.CrtYd" user "F.Courtyard")
    (48 "B.Fab" user)
    (49 "F.Fab" user)
  )
	(footprint "kria-k26-devboard-footprints:UQFN-16-1.8x2.6mm_P0.4mm_Texas_RSV0016A" (layer "B.Cu")
    (at 93.6 85.9 180)
    (descr "https://www.ti.com/lit/ds/symlink/sn74avch4t245-ep.pdf?ts=1679484181203&ref_url=https%253A%252F%252Fwww.ti.com%252Fproduct%252FSN74AVCH4T245-EP%253Futm_source%253Dgoogle%2526utm_medium%253Dcpc%2526utm_campaign%253Dasc-int-null-prodfolderdynamic-cpc-pf-google-wwe_int%2526utm_content%253Dprodfolddynamic%2526ds_k%253DDYNAMIC%2BSEARCH%2BADS%2526DCM%253Dyes%2526gclid%253DCjwKCAjwzuqgBhAcEiwAdj5dRvR_WgyvqqhLxMx8zfbFv2a6tg33JIMv01Bn4M1kA4JzW1nDDW7OzhoCRbkQAvD_BwE%2526gclsrc%253Daw.ds")
    (property "Author" "Antmicro")
    (property "License" "Apache-2.0")
    (property "MPN" "74AVC4T245RSVRG4")
    (property "Manufacturer" "Texas Instruments")
    (property "Sheetfile" "dp.kicad_sch")
    (property "Sheetname" "Display Port")
    (property "ki_description" "4-Bit Dual-Supply Bus Transceiver With Configurable Voltage Translation and 3-State Outputs, TSSOP-16")
    (property "ki_keywords" "Noninverting Bidirectional")
    (attr smd)
    (fp_text reference "U1" (at -0.83 -2.58) (layer "B.SilkS")
        (effects (font (size 0.7 0.7) (thickness 0.15)) (justify left bottom mirror))
    )
    (fp_text value "74AVC4T245_UQFN" (at -1.25 -2.5) (layer "B.Fab") hide
        (effects (font (size 0.7 0.7) (thickness 0.15)) (justify left bottom mirror))
    )
    (fp_text user "." (at -1.45 0.75) (layer "B.SilkS")
        (effects (font (size 0.7 0.7) (thickness 0.15)) (justify left bottom mirror))
    )
    (fp_text user "License: Apache-2.0" (at -1.25 -6.25) (layer "B.Fab") hide
        (effects (font (size 0.7 0.7) (thickness 0.15)) (justify left bottom mirror))
    )
    (fp_text user "Author: Antmicro" (at -1.25 -5) (layer "B.Fab") hide
        (effects (font (size 0.7 0.7) (thickness 0.15)) (justify left bottom mirror))
    )
    (fp_text user "${REFERENCE}" (at -1.25 -3.75) (layer "B.Fab") hide
        (effects (font (size 0.7 0.7) (thickness 0.15)) (justify left bottom mirror))
    )
    (fp_line (start -0.9 -1.2995) (end -0.9 -0.8)
      (stroke (width 0.15) (type solid)) (layer "B.SilkS"))
    (fp_line (start -0.8 -1.2995) (end -0.9 -1.2995)
      (stroke (width 0.15) (type solid)) (layer "B.SilkS"))
    (fp_line (start -0.8 1.3) (end -0.9 1.3)
      (stroke (width 0.15) (type solid)) (layer "B.SilkS"))
    (fp_line (start 0.8 -1.3) (end 0.899 -1.3)
      (stroke (width 0.15) (type solid)) (layer "B.SilkS"))
    (fp_line (start 0.8 1.3) (end 0.9 1.3)
      (stroke (width 0.15) (type solid)) (layer "B.SilkS"))
    (fp_line (start 0.9 -0.8) (end 0.899 -1.3)
      (stroke (width 0.15) (type solid)) (layer "B.SilkS"))
    (fp_line (start 0.9 1.3) (end 0.9 0.8005)
      (stroke (width 0.15) (type solid)) (layer "B.SilkS"))
    (fp_rect (start -1.25 1.65) (end 1.25 -1.65)
      (stroke (width 0.05) (type solid)) (fill none) (layer "B.CrtYd"))
    (fp_line (start -0.902 -1.3) (end -0.902 1.301)
      (stroke (width 0.15) (type solid)) (layer "B.Fab"))
    (fp_line (start 0.9 -1.3) (end -0.902 -1.3)
      (stroke (width 0.15) (type solid)) (layer "B.Fab"))
    (fp_line (start 0.9 -1.3) (end 0.9 1.301)
      (stroke (width 0.15) (type solid)) (layer "B.Fab"))
    (fp_line (start 0.9 1.301) (end -0.902 1.301)
      (stroke (width 0.15) (type solid)) (layer "B.Fab"))
    (pad "1" smd roundrect (at -0.75 0.6 180) (size 0.7 0.2) (layers "B.Cu" "B.Paste" "B.Mask") (roundrect_rratio 0.2272727273)
      (net 1 "GND") (pinfunction "1~{OE}") (pintype "input"))
    (pad "2" smd roundrect (at -0.802 0.202 180) (size 0.6 0.2) (layers "B.Cu" "B.Paste" "B.Mask") (roundrect_rratio 0.2272727273)
      (net 15 "PS_3V3") (pinfunction "VCCB") (pintype "power_in"))
    (pad "3" smd roundrect (at -0.802 -0.2 180) (size 0.6 0.2) (layers "B.Cu" "B.Paste" "B.Mask") (roundrect_rratio 0.2272727273)
      (net 17 "PS_1V8") (pinfunction "VCCA") (pintype "power_in"))
    (pad "4" smd roundrect (at -0.802 -0.598 180) (size 0.6 0.2) (layers "B.Cu" "B.Paste" "B.Mask") (roundrect_rratio 0.2272727273)
      (net 17 "PS_1V8") (pinfunction "1DIR") (pintype "input"))
    (pad "5" smd roundrect (at -0.6 -1.199 90) (size 0.6 0.2) (layers "B.Cu" "B.Paste" "B.Mask") (roundrect_rratio 0.2272727273)
      (net 1 "GND") (pinfunction "2DIR") (pintype "input"))
    (pad "6" smd roundrect (at -0.202 -1.199 90) (size 0.6 0.2) (layers "B.Cu" "B.Paste" "B.Mask") (roundrect_rratio 0.2272727273)
      (net 116 "/Display Port/MIO27") (pinfunction "1A1") (pintype "bidirectional"))
    (pad "7" smd roundrect (at 0.2 -1.199 90) (size 0.6 0.2) (layers "B.Cu" "B.Paste" "B.Mask") (roundrect_rratio 0.2272727273)
      (net 111 "/Display Port/MIO29") (pinfunction "1A2") (pintype "bidirectional"))
    (pad "8" smd roundrect (at 0.598 -1.199 90) (size 0.6 0.2) (layers "B.Cu" "B.Paste" "B.Mask") (roundrect_rratio 0.2272727273)
      (net 112 "/Display Port/MIO30") (pinfunction "2A1") (pintype "bidirectional"))
    (pad "9" smd roundrect (at 0.8 -0.598 180) (size 0.6 0.2) (layers "B.Cu" "B.Paste" "B.Mask") (roundrect_rratio 0.2272727273)
      (net 117 "/Display Port/MIO28") (pinfunction "2A2") (pintype "bidirectional"))
    (pad "10" smd roundrect (at 0.8 -0.2 180) (size 0.6 0.2) (layers "B.Cu" "B.Paste" "B.Mask") (roundrect_rratio 0.2272727273)
      (net 1 "GND") (pinfunction "GND") (pintype "power_in"))
    (pad "11" smd roundrect (at 0.8 0.202 180) (size 0.6 0.2) (layers "B.Cu" "B.Paste" "B.Mask") (roundrect_rratio 0.2272727273)
      (net 1 "GND") (pinfunction "GND") (pintype "passive"))
    (pad "12" smd roundrect (at 0.8 0.6 180) (size 0.6 0.2) (layers "B.Cu" "B.Paste" "B.Mask") (roundrect_rratio 0.2272727273)
      (net 105 "/Display Port/DP_HPD") (pinfunction "2B2") (pintype "bidirectional"))
    (pad "13" smd roundrect (at 0.598 1.2 90) (size 0.6 0.2) (layers "B.Cu" "B.Paste" "B.Mask") (roundrect_rratio 0.2272727273)
      (net 126 "/Display Port/DP_AUX_IN") (pinfunction "2B1") (pintype "bidirectional"))
    (pad "14" smd roundrect (at 0.2 1.2 90) (size 0.6 0.2) (layers "B.Cu" "B.Paste" "B.Mask") (roundrect_rratio 0.2272727273)
      (net 125 "/Display Port/DP_OE") (pinfunction "1B2") (pintype "bidirectional"))
    (pad "15" smd roundrect (at -0.202 1.2 90) (size 0.6 0.2) (layers "B.Cu" "B.Paste" "B.Mask") (roundrect_rratio 0.2272727273)
      (net 124 "/Display Port/DP_AUX_OUT") (pinfunction "1B1") (pintype "bidirectional"))
    (pad "16" smd roundrect (at -0.6 1.2 90) (size 0.6 0.2) (layers "B.Cu" "B.Paste" "B.Mask") (roundrect_rratio 0.2272727273)
      (net 1 "GND") (pinfunction "2~{OE}") (pintype "input"))
  )
	(footprint "kria-k26-devboard-footprints:R_0402_1005Metric" (layer "B.Cu")
    (at 115.7 141.1 180)
    (descr "Resistor SMD 0402")
    (tags "resistor SMD 0402")
    (property "Author" "Antmicro")
    (property "License" "Apache-2.0")
    (property "MPN" "CR0402-FX-1002GLF")
    (property "Manufacturer" "Bourns")
    (property "Sheetfile" "reset.kicad_sch")
    (property "Sheetname" "Reset logic")
    (property "Tolerance" "1%")
    (property "Val" "10k")
    (property "ki_description" "10k resistor in 0402 package with 1% tolerance")
    (attr smd)
    (fp_text reference "R96" (at -3.07 -0.34) (layer "B.SilkS")
        (effects (font (size 0.7 0.7) (thickness 0.15)) (justify left bottom mirror))
    )
    (fp_text value "R_10k_0402" (at 0 -1.4) (layer "B.Fab") hide
        (effects (font (size 0.7 0.7) (thickness 0.15)) (justify left bottom mirror))
    )
    (fp_text user "Author: Antmicro" (at -0.95 -4.169) (layer "B.Fab") hide
        (effects (font (size 0.7 0.7) (thickness 0.15)) (justify left bottom mirror))
    )
    (fp_text user "${REFERENCE}" (at -0.95 -3.168) (layer "B.Fab") hide
        (effects (font (size 0.7 0.7) (thickness 0.15)) (justify left bottom mirror))
    )
    (fp_text user "License: Apache-2.0" (at -0.95 -5.169) (layer "B.Fab") hide
        (effects (font (size 0.7 0.7) (thickness 0.15)) (justify left bottom mirror))
    )
    (fp_rect (start -0.93 0.47) (end 0.93 -0.47)
      (stroke (width 0.05) (type solid)) (fill none) (layer "B.CrtYd"))
    (fp_rect (start -0.5 0.25) (end 0.5 -0.25)
      (stroke (width 0.15) (type solid)) (fill none) (layer "B.Fab"))
    (pad "1" smd roundrect (at -0.485 0 180) (size 0.59 0.64) (layers "B.Cu" "B.Paste" "B.Mask") (roundrect_rratio 0.25)
      (net 17 "PS_1V8") (pintype "passive"))
    (pad "2" smd roundrect (at 0.485 0 180) (size 0.59 0.64) (layers "B.Cu" "B.Paste" "B.Mask") (roundrect_rratio 0.25)
      (net 176 "/Ethernet/~{ETH_RESET}") (pintype "passive"))
  )
	(footprint "kria-k26-devboard-footprints:R_0402_1005Metric" (layer "B.Cu")
    (at 115.7 139.1 180)
    (descr "Resistor SMD 0402")
    (tags "resistor SMD 0402")
    (property "Author" "Antmicro")
    (property "License" "Apache-2.0")
    (property "MPN" "CR0402-FX-1002GLF")
    (property "Manufacturer" "Bourns")
    (property "Sheetfile" "reset.kicad_sch")
    (property "Sheetname" "Reset logic")
    (property "Tolerance" "1%")
    (property "Val" "10k")
    (property "ki_description" "10k resistor in 0402 package with 1% tolerance")
    (attr smd)
    (fp_text reference "R95" (at -3.07 -0.34) (layer "B.SilkS")
        (effects (font (size 0.7 0.7) (thickness 0.15)) (justify left bottom mirror))
    )
    (fp_text value "R_10k_0402" (at 0 -1.4) (layer "B.Fab") hide
        (effects (font (size 0.7 0.7) (thickness 0.15)) (justify left bottom mirror))
    )
    (fp_text user "License: Apache-2.0" (at -0.95 -5.169) (layer "B.Fab") hide
        (effects (font (size 0.7 0.7) (thickness 0.15)) (justify left bottom mirror))
    )
    (fp_text user "${REFERENCE}" (at -0.95 -3.168) (layer "B.Fab") hide
        (effects (font (size 0.7 0.7) (thickness 0.15)) (justify left bottom mirror))
    )
    (fp_text user "Author: Antmicro" (at -0.95 -4.169) (layer "B.Fab") hide
        (effects (font (size 0.7 0.7) (thickness 0.15)) (justify left bottom mirror))
    )
    (fp_rect (start -0.93 0.47) (end 0.93 -0.47)
      (stroke (width 0.05) (type solid)) (fill none) (layer "B.CrtYd"))
    (fp_rect (start -0.5 0.25) (end 0.5 -0.25)
      (stroke (width 0.15) (type solid)) (fill none) (layer "B.Fab"))
    (pad "1" smd roundrect (at -0.485 0 180) (size 0.59 0.64) (layers "B.Cu" "B.Paste" "B.Mask") (roundrect_rratio 0.25)
      (net 15 "PS_3V3") (pintype "passive"))
    (pad "2" smd roundrect (at 0.485 0 180) (size 0.59 0.64) (layers "B.Cu" "B.Paste" "B.Mask") (roundrect_rratio 0.25)
      (net 175 "/Reset logic/~{USB_HUB_RESET}") (pintype "passive"))
  )
	(footprint "kria-k26-devboard-footprints:R_0402_1005Metric" (layer "B.Cu")
    (at 111.65 138.25)
    (descr "Resistor SMD 0402")
    (tags "resistor SMD 0402")
    (property "Author" "Antmicro")
    (property "License" "Apache-2.0")
    (property "MPN" "CR0402-FX-1002GLF")
    (property "Manufacturer" "Bourns")
    (property "Sheetfile" "reset.kicad_sch")
    (property "Sheetname" "Reset logic")
    (property "Tolerance" "1%")
    (property "Val" "10k")
    (property "ki_description" "10k resistor in 0402 package with 1% tolerance")
    (attr smd)
    (fp_text reference "R94" (at 3.01 0.35 180) (layer "B.SilkS")
        (effects (font (size 0.7 0.7) (thickness 0.15)) (justify left bottom mirror))
    )
    (fp_text value "R_10k_0402" (at 0 -1.4 180) (layer "B.Fab") hide
        (effects (font (size 0.7 0.7) (thickness 0.15)) (justify left bottom mirror))
    )
    (fp_text user "License: Apache-2.0" (at -0.95 -5.169 180) (layer "B.Fab") hide
        (effects (font (size 0.7 0.7) (thickness 0.15)) (justify left bottom mirror))
    )
    (fp_text user "${REFERENCE}" (at -0.95 -3.168 180) (layer "B.Fab") hide
        (effects (font (size 0.7 0.7) (thickness 0.15)) (justify left bottom mirror))
    )
    (fp_text user "Author: Antmicro" (at -0.95 -4.169 180) (layer "B.Fab") hide
        (effects (font (size 0.7 0.7) (thickness 0.15)) (justify left bottom mirror))
    )
    (fp_rect (start -0.93 0.47) (end 0.93 -0.47)
      (stroke (width 0.05) (type solid)) (fill none) (layer "B.CrtYd"))
    (fp_rect (start -0.5 0.25) (end 0.5 -0.25)
      (stroke (width 0.15) (type solid)) (fill none) (layer "B.Fab"))
    (pad "1" smd roundrect (at -0.485 0) (size 0.59 0.64) (layers "B.Cu" "B.Paste" "B.Mask") (roundrect_rratio 0.25)
      (net 17 "PS_1V8") (pintype "passive"))
    (pad "2" smd roundrect (at 0.485 0) (size 0.59 0.64) (layers "B.Cu" "B.Paste" "B.Mask") (roundrect_rratio 0.25)
      (net 178 "/Reset logic/~{USB_PHY_RESET}") (pintype "passive"))
  )
	(footprint "kria-k26-devboard-footprints:R_0402_1005Metric" (layer "B.Cu")
    (at 111.2 139.665 -90)
    (descr "Resistor SMD 0402")
    (tags "resistor SMD 0402")
    (property "Author" "Antmicro")
    (property "License" "Apache-2.0")
    (property "MPN" "CR0402-FX-1002GLF")
    (property "Manufacturer" "Bourns")
    (property "Sheetfile" "reset.kicad_sch")
    (property "Sheetname" "Reset logic")
    (property "Tolerance" "1%")
    (property "Val" "10k")
    (property "ki_description" "10k resistor in 0402 package with 1% tolerance")
    (attr smd)
    (fp_text reference "R92" (at -0.485 -1.33 90) (layer "B.SilkS")
        (effects (font (size 0.7 0.7) (thickness 0.15)) (justify left bottom mirror))
    )
    (fp_text value "R_10k_0402" (at 0 -1.4 90) (layer "B.Fab") hide
        (effects (font (size 0.7 0.7) (thickness 0.15)) (justify left bottom mirror))
    )
    (fp_text user "License: Apache-2.0" (at -0.95 -5.169 90) (layer "B.Fab") hide
        (effects (font (size 0.7 0.7) (thickness 0.15)) (justify left bottom mirror))
    )
    (fp_text user "Author: Antmicro" (at -0.95 -4.169 90) (layer "B.Fab") hide
        (effects (font (size 0.7 0.7) (thickness 0.15)) (justify left bottom mirror))
    )
    (fp_text user "${REFERENCE}" (at -0.95 -3.168 90) (layer "B.Fab") hide
        (effects (font (size 0.7 0.7) (thickness 0.15)) (justify left bottom mirror))
    )
    (fp_rect (start -0.93 0.47) (end 0.93 -0.47)
      (stroke (width 0.05) (type solid)) (fill none) (layer "B.CrtYd"))
    (fp_rect (start -0.5 0.25) (end 0.5 -0.25)
      (stroke (width 0.15) (type solid)) (fill none) (layer "B.Fab"))
    (pad "1" smd roundrect (at -0.485 0 270) (size 0.59 0.64) (layers "B.Cu" "B.Paste" "B.Mask") (roundrect_rratio 0.25)
      (net 15 "PS_3V3") (pintype "passive"))
    (pad "2" smd roundrect (at 0.485 0 270) (size 0.59 0.64) (layers "B.Cu" "B.Paste" "B.Mask") (roundrect_rratio 0.25)
      (net 177 "/Reset logic/~{SD_CARD_RESET}") (pintype "passive"))
  )
	(footprint "kria-k26-devboard-footprints:C_0402_1005Metric" (layer "B.Cu")
    (at 108.95 144.9)
    (descr "Capacitor SMD 0402")
    (tags "capacitor SMD 0402")
    (property "Author" "Antmicro")
    (property "Dielectric" "X5R")
    (property "License" "Apache-2.0")
    (property "MPN" "GRM155R61H104KE14D")
    (property "Manufacturer" "Murata")
    (property "Sheetfile" "reset.kicad_sch")
    (property "Sheetname" "Reset logic")
    (property "Val" "100n")
    (property "Voltage" "50V")
    (property "ki_description" " ")
    (attr smd)
    (fp_text reference "C138" (at 1.39 1.35 180) (layer "B.SilkS")
        (effects (font (size 0.7 0.7) (thickness 0.15)) (justify left bottom mirror))
    )
    (fp_text value "C_100n_0402" (at 0 -1.4 180) (layer "B.Fab") hide
        (effects (font (size 0.7 0.7) (thickness 0.15)) (justify left bottom mirror))
    )
    (fp_text user "Author: Antmicro" (at -0.932 -4.17 180) (layer "B.Fab") hide
        (effects (font (size 0.7 0.7) (thickness 0.15)) (justify left bottom mirror))
    )
    (fp_text user "License: Apache-2.0" (at -0.932 -5.17 180) (layer "B.Fab") hide
        (effects (font (size 0.7 0.7) (thickness 0.15)) (justify left bottom mirror))
    )
    (fp_text user "${REFERENCE}" (at -0.932 -3.168 180) (layer "B.Fab") hide
        (effects (font (size 0.7 0.7) (thickness 0.15)) (justify left bottom mirror))
    )
    (fp_rect (start -0.94 0.47) (end 0.94 -0.47)
      (stroke (width 0.05) (type solid)) (fill none) (layer "B.CrtYd"))
    (fp_rect (start -0.499 0.249) (end 0.499 -0.249)
      (stroke (width 0.15) (type solid)) (fill none) (layer "B.Fab"))
    (pad "1" smd roundrect (at -0.484 0) (size 0.59 0.64) (layers "B.Cu" "B.Paste" "B.Mask") (roundrect_rratio 0.25)
      (net 15 "PS_3V3") (pintype "passive"))
    (pad "2" smd roundrect (at 0.484 0) (size 0.59 0.64) (layers "B.Cu" "B.Paste" "B.Mask") (roundrect_rratio 0.25)
      (net 1 "GND") (pintype "passive"))
  )
	(footprint "kria-k26-devboard-footprints:R_0402_1005Metric" (layer "B.Cu")
    (at 110.4 142.4 90)
    (descr "Resistor SMD 0402")
    (tags "resistor SMD 0402")
    (property "Author" "Antmicro")
    (property "License" "Apache-2.0")
    (property "MPN" "CR0402-FX-1003GLF")
    (property "Manufacturer" "Bourns")
    (property "Sheetfile" "reset.kicad_sch")
    (property "Sheetname" "Reset logic")
    (property "Tolerance" "1%")
    (property "Val" "100k")
    (property "ki_description" "100k resistor in 0402 package with 1% tolerance")
    (attr smd)
    (fp_text reference "R87" (at 1.14 1.34 270) (layer "B.SilkS")
        (effects (font (size 0.7 0.7) (thickness 0.15)) (justify left bottom mirror))
    )
    (fp_text value "R_100k_0402" (at 0 -1.4 270) (layer "B.Fab") hide
        (effects (font (size 0.7 0.7) (thickness 0.15)) (justify left bottom mirror))
    )
    (fp_text user "License: Apache-2.0" (at -0.95 -5.169 270) (layer "B.Fab") hide
        (effects (font (size 0.7 0.7) (thickness 0.15)) (justify left bottom mirror))
    )
    (fp_text user "${REFERENCE}" (at -0.95 -3.168 270) (layer "B.Fab") hide
        (effects (font (size 0.7 0.7) (thickness 0.15)) (justify left bottom mirror))
    )
    (fp_text user "Author: Antmicro" (at -0.95 -4.169 270) (layer "B.Fab") hide
        (effects (font (size 0.7 0.7) (thickness 0.15)) (justify left bottom mirror))
    )
    (fp_rect (start -0.93 0.47) (end 0.93 -0.47)
      (stroke (width 0.05) (type solid)) (fill none) (layer "B.CrtYd"))
    (fp_rect (start -0.5 0.25) (end 0.5 -0.25)
      (stroke (width 0.15) (type solid)) (fill none) (layer "B.Fab"))
    (pad "1" smd roundrect (at -0.485 0 90) (size 0.59 0.64) (layers "B.Cu" "B.Paste" "B.Mask") (roundrect_rratio 0.25)
      (net 1 "GND") (pintype "passive"))
    (pad "2" smd roundrect (at 0.485 0 90) (size 0.59 0.64) (layers "B.Cu" "B.Paste" "B.Mask") (roundrect_rratio 0.25)
      (net 675 "Net-(U33-1A1)") (pintype "passive"))
  )
)
